(kicad_pcb
	(version 20260206)
	(generator "pcbnew")
	(generator_version "10.0")
	(general
		(thickness 1.6)
		(legacy_teardrops no)
	)
	(paper "A4")
	(title_block
		(title "04192023_DAF0TMB3IC0_F0TG_MB_C_brd_V02_OCP.brd")
		(comment 1 "Grand Teton / footprints 3703-3708 of 8354")
	)
	(layers
		(0 "F.Cu" signal "TOP")
		(4 "In1.Cu" signal "GND")
		(6 "In2.Cu" signal "IN1")
		(8 "In3.Cu" signal "GND1")
		(10 "In4.Cu" signal "IN2")
		(12 "In5.Cu" signal "GND2")
		(14 "In6.Cu" signal "IN3")
		(16 "In7.Cu" signal "GND3")
		(18 "In8.Cu" signal "VCC")
		(20 "In9.Cu" signal "VCC1")
		(22 "In10.Cu" signal "GND4")
		(24 "In11.Cu" signal "IN4")
		(26 "In12.Cu" signal "GND5")
		(28 "In13.Cu" signal "IN5")
		(30 "In14.Cu" signal "GND6")
		(32 "In15.Cu" signal "IN6")
		(34 "In16.Cu" signal "GND7")
		(2 "B.Cu" signal "BOTTOM")
		(9 "F.Adhes" user "F.Adhesive")
		(11 "B.Adhes" user "B.Adhesive")
		(13 "F.Paste" user "Package Geometry/Pastemask Top")
		(15 "B.Paste" user "Package Geometry/Pastemask Bottom")
		(5 "F.SilkS" user "Ref Des/Silkscreen Top")
		(7 "B.SilkS" user "Ref Des/Silkscreen Bottom")
		(1 "F.Mask" user "Board Geometry/Soldermask Top")
		(3 "B.Mask" user "Board Geometry/Soldermask Bottom")
		(17 "Dwgs.User" user "User.Drawings")
		(19 "Cmts.User" user "User.Comments")
		(21 "Eco1.User" user "User.Eco1")
		(23 "Eco2.User" user "User.Eco2")
		(25 "Edge.Cuts" user "Board Geometry/Outline")
		(27 "Margin" user)
		(31 "F.CrtYd" user "Package Geometry/Place Bound Top")
		(29 "B.CrtYd" user "Package Geometry/Place Bound Bottom")
		(35 "F.Fab" user "Ref Des/Assembly Top")
		(33 "B.Fab" user "Ref Des/Assembly Bottom")
	)
	(footprint ""
		(layer "F.Cu")
		(at 504.058428 -298.345606 90)
		(property "Reference" "X3"
			(at -1.94437 1.232916 0)
			(unlocked yes)
			(layer "F.SilkS")
			(effects
				(font
					(size 0.7874 0.5842)
					(thickness 0.1524)
				)
				(justify left)
			)
		)
		(property "Value" ""
			(at 0 0 90)
			(layer "F.Fab")
			(effects
				(font
					(size 1.27 1.27)
				)
			)
		)
		(property "User Part Number" "N_A"
			(at 1.30175 1.27 180)
			(unlocked yes)
			(layer "Cmts.User")
			(hide yes)
			(effects
				(font
					(size 0.635 0.4064)
					(thickness 0.1524)
				)
			)
		)
		(property "Device Type" "TP_TDR_4P_FTS_TH-TP_TDR_4P_DIP,EMPTY,TP15"
			(at 1.30175 1.27 180)
			(unlocked yes)
			(layer "F.Fab")
			(hide yes)
			(effects
				(font
					(size 0.635 0.4064)
					(thickness 0.1524)
				)
			)
		)
		(duplicate_pad_numbers_are_jumpers no)
		(fp_line
			(start 2.54 -1.27)
			(end 0 -1.27)
			(stroke
				(width 0.1524)
				(type default)
			)
			(layer "F.SilkS")
		)
		(fp_line
			(start 0 -1.27)
			(end 0 -0.635)
			(stroke
				(width 0.1524)
				(type default)
			)
			(layer "F.SilkS")
		)
		(fp_line
			(start 2.54 -1.1303)
			(end 2.54 -1.27)
			(stroke
				(width 0.1524)
				(type default)
			)
			(layer "F.SilkS")
		)
		(fp_line
			(start 0 0.635)
			(end 0 1.905)
			(stroke
				(width 0.1524)
				(type default)
			)
			(layer "F.SilkS")
		)
		(fp_line
			(start 2.54 1.4097)
			(end 2.54 1.1303)
			(stroke
				(width 0.1524)
				(type default)
			)
			(layer "F.SilkS")
		)
		(fp_line
			(start 0 3.175)
			(end 0 3.81)
			(stroke
				(width 0.1524)
				(type default)
			)
			(layer "F.SilkS")
		)
		(fp_line
			(start 2.54 3.81)
			(end 2.54 3.6703)
			(stroke
				(width 0.1524)
				(type default)
			)
			(layer "F.SilkS")
		)
		(fp_line
			(start 0 3.81)
			(end 2.54 3.81)
			(stroke
				(width 0.1524)
				(type default)
			)
			(layer "F.SilkS")
		)
		(fp_poly
			(pts
				(xy -0.761746 0) (xy -2.285746 0.762) (xy -2.285746 -0.762)
			)
			(stroke
				(width 0)
				(type default)
			)
			(fill yes)
			(layer "F.SilkS")
		)
		(fp_line
			(start 2.54 -1.27)
			(end 0 -1.27)
			(stroke
				(width 0.1)
				(type default)
			)
			(layer "F.Fab")
		)
		(fp_line
			(start 0 -1.27)
			(end 0 3.81)
			(stroke
				(width 0.1)
				(type default)
			)
			(layer "F.Fab")
		)
		(fp_line
			(start 2.54 3.81)
			(end 2.54 -1.27)
			(stroke
				(width 0.1)
				(type default)
			)
			(layer "F.Fab")
		)
		(fp_line
			(start 0 3.81)
			(end 2.54 3.81)
			(stroke
				(width 0.1)
				(type default)
			)
			(layer "F.Fab")
		)
		(fp_poly
			(pts
				(xy -0.761746 0) (xy -2.285746 -0.762) (xy -2.285746 0.762)
			)
			(stroke
				(width 0)
				(type default)
			)
			(fill yes)
			(layer "F.Fab")
		)
		(pad "1" thru_hole circle
			(at 0 0 90)
			(size 1.0033 1.0033)
			(drill 0.249936)
			(layers "*.Cu" "*.Mask")
			(remove_unused_layers no)
			(net "TDR_DIFF_80_IN2_DP")
			(clearance 0.10795)
			(thermal_gap 0.10795)
			(padstack
				(mode front_inner_back)
				(layer "Inner"
					(shape circle)
					(size 0.8001 0.8001)
					(clearance 0.1524)
				)
				(layer "B.Cu"
					(shape circle)
					(size 1.0033 1.0033)
					(clearance 0.10795)
				)
			)
		)
		(pad "2" thru_hole circle
			(at 2.54 0 90)
			(size 1.9939 1.9939)
			(drill 0.249936)
			(layers "*.Cu" "*.Mask")
			(remove_unused_layers no)
			(net "T1_GND")
			(clearance 0.10795)
			(thermal_gap 0.10795)
			(padstack
				(mode front_inner_back)
				(layer "Inner"
					(shape circle)
					(size 0.8001 0.8001)
					(clearance 0.1524)
				)
				(layer "B.Cu"
					(shape circle)
					(size 1.9939 1.9939)
					(clearance 0.10795)
				)
			)
		)
		(pad "3" thru_hole circle
			(at 2.54 2.54 90)
			(size 1.9939 1.9939)
			(drill 0.249936)
			(layers "*.Cu" "*.Mask")
			(remove_unused_layers no)
			(net "T1_GND")
			(clearance 0.10795)
			(thermal_gap 0.10795)
			(padstack
				(mode front_inner_back)
				(layer "Inner"
					(shape circle)
					(size 0.8001 0.8001)
					(clearance 0.1524)
				)
				(layer "B.Cu"
					(shape circle)
					(size 1.9939 1.9939)
					(clearance 0.10795)
				)
			)
		)
		(pad "4" thru_hole circle
			(at 0 2.54 90)
			(size 1.0033 1.0033)
			(drill 0.249936)
			(layers "*.Cu" "*.Mask")
			(remove_unused_layers no)
			(net "TDR_DIFF_80_IN2_DN")
			(clearance 0.10795)
			(thermal_gap 0.10795)
			(padstack
				(mode front_inner_back)
				(layer "Inner"
					(shape circle)
					(size 0.8001 0.8001)
					(clearance 0.1524)
				)
				(layer "B.Cu"
					(shape circle)
					(size 1.0033 1.0033)
					(clearance 0.10795)
				)
			)
		)
	)
	(footprint ""
		(layer "F.Cu")
		(at 364.314486 -409.931616 180)
		(property "Reference" "C9002"
			(at 0 0 180)
			(layer "F.SilkS")
			(hide yes)
			(effects
				(font
					(size 1.27 1.27)
				)
			)
		)
		(property "Value" ""
			(at 0 0 180)
			(layer "F.Fab")
			(effects
				(font
					(size 1.27 1.27)
				)
			)
		)
		(duplicate_pad_numbers_are_jumpers no)
		(fp_line
			(start 0.7874 0.4064)
			(end -0.7874 0.4064)
			(stroke
				(width 0.1524)
				(type default)
			)
			(layer "F.SilkS")
		)
		(fp_line
			(start 0.7874 -0.4064)
			(end 0.7874 0.4064)
			(stroke
				(width 0.1524)
				(type default)
			)
			(layer "F.SilkS")
		)
		(fp_line
			(start -0.7874 0.4064)
			(end -0.7874 -0.4064)
			(stroke
				(width 0.1524)
				(type default)
			)
			(layer "F.SilkS")
		)
		(fp_line
			(start -0.7874 -0.4064)
			(end 0.7874 -0.4064)
			(stroke
				(width 0.1524)
				(type default)
			)
			(layer "F.SilkS")
		)
		(fp_line
			(start 0.67945 0.3048)
			(end 0.120396 0.3048)
			(stroke
				(width 0.1)
				(type default)
			)
			(layer "F.Fab")
		)
		(fp_line
			(start 0.67945 -0.3048)
			(end 0.67945 0.3048)
			(stroke
				(width 0.1)
				(type default)
			)
			(layer "F.Fab")
		)
		(fp_line
			(start 0.12065 -0.2794)
			(end 0.12065 -0.3048)
			(stroke
				(width 0.1)
				(type default)
			)
			(layer "F.Fab")
		)
		(fp_line
			(start 0.12065 -0.3048)
			(end 0.67945 -0.3048)
			(stroke
				(width 0.1)
				(type default)
			)
			(layer "F.Fab")
		)
		(fp_line
			(start 0.120396 0.3048)
			(end 0.120396 0.2794)
			(stroke
				(width 0.1)
				(type default)
			)
			(layer "F.Fab")
		)
		(fp_line
			(start 0.120396 0.2794)
			(end -0.12065 0.2794)
			(stroke
				(width 0.1)
				(type default)
			)
			(layer "F.Fab")
		)
		(fp_line
			(start -0.12065 0.3048)
			(end -0.67945 0.3048)
			(stroke
				(width 0.1)
				(type default)
			)
			(layer "F.Fab")
		)
		(fp_line
			(start -0.12065 0.2794)
			(end -0.12065 0.3048)
			(stroke
				(width 0.1)
				(type default)
			)
			(layer "F.Fab")
		)
		(fp_line
			(start -0.12065 -0.2794)
			(end 0.12065 -0.2794)
			(stroke
				(width 0.1)
				(type default)
			)
			(layer "F.Fab")
		)
		(fp_line
			(start -0.12065 -0.305054)
			(end -0.12065 -0.2794)
			(stroke
				(width 0.1)
				(type default)
			)
			(layer "F.Fab")
		)
		(fp_line
			(start -0.67945 0.3048)
			(end -0.67945 -0.305054)
			(stroke
				(width 0.1)
				(type default)
			)
			(layer "F.Fab")
		)
		(fp_line
			(start -0.67945 -0.305054)
			(end -0.12065 -0.305054)
			(stroke
				(width 0.1)
				(type default)
			)
			(layer "F.Fab")
		)
		(pad "1" smd circle
			(at -0.40005 0 180)
			(size 0 0)
			(layers "F.Cu" "F.Mask" "F.Paste")
			(net "PRSNT_CABLE_GPU_A3_ISO_N")
		)
		(pad "2" smd circle
			(at 0.40005 0 180)
			(size 0 0)
			(layers "F.Cu" "F.Mask" "F.Paste")
			(net "GND")
		)
	)
	(footprint ""
		(layer "F.Cu")
		(at 161.06013 -352.668078 -90)
		(property "Reference" "R8382"
			(at 0 0 270)
			(layer "F.SilkS")
			(hide yes)
			(effects
				(font
					(size 1.27 1.27)
				)
			)
		)
		(property "Value" ""
			(at 0 0 270)
			(layer "F.Fab")
			(effects
				(font
					(size 1.27 1.27)
				)
			)
		)
		(duplicate_pad_numbers_are_jumpers no)
		(fp_line
			(start -0.7874 0.4064)
			(end -0.7874 -0.4064)
			(stroke
				(width 0.1524)
				(type default)
			)
			(layer "F.SilkS")
		)
		(fp_line
			(start 0.7874 0.4064)
			(end -0.7874 0.4064)
			(stroke
				(width 0.1524)
				(type default)
			)
			(layer "F.SilkS")
		)
		(fp_line
			(start -0.7874 -0.4064)
			(end 0.7874 -0.4064)
			(stroke
				(width 0.1524)
				(type default)
			)
			(layer "F.SilkS")
		)
		(fp_line
			(start 0.7874 -0.4064)
			(end 0.7874 0.4064)
			(stroke
				(width 0.1524)
				(type default)
			)
			(layer "F.SilkS")
		)
		(fp_line
			(start -0.67945 0.3048)
			(end -0.67945 -0.305054)
			(stroke
				(width 0.1)
				(type default)
			)
			(layer "F.Fab")
		)
		(fp_line
			(start -0.12065 0.3048)
			(end -0.67945 0.3048)
			(stroke
				(width 0.1)
				(type default)
			)
			(layer "F.Fab")
		)
		(fp_line
			(start 0.120396 0.3048)
			(end 0.120396 0.2794)
			(stroke
				(width 0.1)
				(type default)
			)
			(layer "F.Fab")
		)
		(fp_line
			(start 0.67945 0.3048)
			(end 0.120396 0.3048)
			(stroke
				(width 0.1)
				(type default)
			)
			(layer "F.Fab")
		)
		(fp_line
			(start -0.12065 0.2794)
			(end -0.12065 0.3048)
			(stroke
				(width 0.1)
				(type default)
			)
			(layer "F.Fab")
		)
		(fp_line
			(start 0.120396 0.2794)
			(end -0.12065 0.2794)
			(stroke
				(width 0.1)
				(type default)
			)
			(layer "F.Fab")
		)
		(fp_line
			(start -0.12065 -0.2794)
			(end 0.12065 -0.2794)
			(stroke
				(width 0.1)
				(type default)
			)
			(layer "F.Fab")
		)
		(fp_line
			(start 0.12065 -0.2794)
			(end 0.12065 -0.3048)
			(stroke
				(width 0.1)
				(type default)
			)
			(layer "F.Fab")
		)
		(fp_line
			(start 0.12065 -0.3048)
			(end 0.67945 -0.3048)
			(stroke
				(width 0.1)
				(type default)
			)
			(layer "F.Fab")
		)
		(fp_line
			(start 0.67945 -0.3048)
			(end 0.67945 0.3048)
			(stroke
				(width 0.1)
				(type default)
			)
			(layer "F.Fab")
		)
		(fp_line
			(start -0.67945 -0.305054)
			(end -0.12065 -0.305054)
			(stroke
				(width 0.1)
				(type default)
			)
			(layer "F.Fab")
		)
		(fp_line
			(start -0.12065 -0.305054)
			(end -0.12065 -0.2794)
			(stroke
				(width 0.1)
				(type default)
			)
			(layer "F.Fab")
		)
		(pad "1" smd circle
			(at -0.40005 0 270)
			(size 0 0)
			(layers "F.Cu" "F.Mask" "F.Paste")
			(net "SMB_SCM_2_R2_SDA")
		)
		(pad "2" smd circle
			(at 0.40005 0 270)
			(size 0 0)
			(layers "F.Cu" "F.Mask" "F.Paste")
			(net "PVDD11_S3_P1_PMSDA_R")
		)
	)
	(footprint ""
		(layer "F.Cu")
		(at 27.7368 -421.069008)
		(property "Reference" "C6005"
			(at 0 0 0)
			(layer "F.SilkS")
			(hide yes)
			(effects
				(font
					(size 1.27 1.27)
				)
			)
		)
		(property "Value" ""
			(at 0 0 0)
			(layer "F.Fab")
			(effects
				(font
					(size 1.27 1.27)
				)
			)
		)
		(duplicate_pad_numbers_are_jumpers no)
		(fp_line
			(start -0.7874 -0.4064)
			(end -0.3556 -0.4064)
			(stroke
				(width 0.1524)
				(type default)
			)
			(layer "F.SilkS")
		)
		(fp_line
			(start 0.7874 -0.215392)
			(end 0.7874 0.4064)
			(stroke
				(width 0.1524)
				(type default)
			)
			(layer "F.SilkS")
		)
		(fp_line
			(start 0.7874 0.4064)
			(end -0.7874 0.4064)
			(stroke
				(width 0.1524)
				(type default)
			)
			(layer "F.SilkS")
		)
		(fp_line
			(start -0.6858 -0.3048)
			(end -0.1016 -0.3048)
			(stroke
				(width 0.1)
				(type default)
			)
			(layer "F.Fab")
		)
		(fp_line
			(start -0.6858 0.3048)
			(end -0.6858 -0.3048)
			(stroke
				(width 0.1)
				(type default)
			)
			(layer "F.Fab")
		)
		(fp_line
			(start -0.1016 -0.3048)
			(end -0.1016 -0.2794)
			(stroke
				(width 0.1)
				(type default)
			)
			(layer "F.Fab")
		)
		(fp_line
			(start -0.1016 -0.2794)
			(end 0.1016 -0.2794)
			(stroke
				(width 0.1)
				(type default)
			)
			(layer "F.Fab")
		)
		(fp_line
			(start -0.1016 0.2794)
			(end -0.1016 0.3048)
			(stroke
				(width 0.1)
				(type default)
			)
			(layer "F.Fab")
		)
		(fp_line
			(start -0.1016 0.3048)
			(end -0.6858 0.3048)
			(stroke
				(width 0.1)
				(type default)
			)
			(layer "F.Fab")
		)
		(fp_line
			(start 0.1016 -0.3048)
			(end 0.6858 -0.3048)
			(stroke
				(width 0.1)
				(type default)
			)
			(layer "F.Fab")
		)
		(fp_line
			(start 0.1016 -0.2794)
			(end 0.1016 -0.3048)
			(stroke
				(width 0.1)
				(type default)
			)
			(layer "F.Fab")
		)
		(fp_line
			(start 0.1016 0.2794)
			(end -0.1016 0.2794)
			(stroke
				(width 0.1)
				(type default)
			)
			(layer "F.Fab")
		)
		(fp_line
			(start 0.1016 0.3048)
			(end 0.1016 0.2794)
			(stroke
				(width 0.1)
				(type default)
			)
			(layer "F.Fab")
		)
		(fp_line
			(start 0.6858 -0.3048)
			(end 0.6858 0.3048)
			(stroke
				(width 0.1)
				(type default)
			)
			(layer "F.Fab")
		)
		(fp_line
			(start 0.6858 0.3048)
			(end 0.1016 0.3048)
			(stroke
				(width 0.1)
				(type default)
			)
			(layer "F.Fab")
		)
		(pad "1" smd rect
			(at -0.40005 0 180)
			(size 0.4572 0.508)
			(layers "F.Cu" "F.Mask" "F.Paste")
			(net "P2E_MB_BMC_TX_BUF2_DP<0>")
		)
		(pad "2" smd rect
			(at 0.40005 0 180)
			(size 0.4572 0.508)
			(layers "F.Cu" "F.Mask" "F.Paste")
			(net "P2E_MB_BMC_TX_BUF_C_DP<0>")
		)
	)
	(footprint ""
		(layer "F.Cu")
		(at 153.543 -104.648)
		(property "Reference" "C9007"
			(at 0 0 0)
			(layer "F.SilkS")
			(hide yes)
			(effects
				(font
					(size 1.27 1.27)
				)
			)
		)
		(property "Value" ""
			(at 0 0 0)
			(layer "F.Fab")
			(effects
				(font
					(size 1.27 1.27)
				)
			)
		)
		(duplicate_pad_numbers_are_jumpers no)
		(fp_line
			(start -0.7874 -0.4064)
			(end 0.7874 -0.4064)
			(stroke
				(width 0.1524)
				(type default)
			)
			(layer "F.SilkS")
		)
		(fp_line
			(start -0.7874 0.4064)
			(end -0.7874 -0.4064)
			(stroke
				(width 0.1524)
				(type default)
			)
			(layer "F.SilkS")
		)
		(fp_line
			(start 0.7874 -0.4064)
			(end 0.7874 0.4064)
			(stroke
				(width 0.1524)
				(type default)
			)
			(layer "F.SilkS")
		)
		(fp_line
			(start 0.7874 0.4064)
			(end -0.7874 0.4064)
			(stroke
				(width 0.1524)
				(type default)
			)
			(layer "F.SilkS")
		)
		(fp_line
			(start -0.67945 -0.305054)
			(end -0.12065 -0.305054)
			(stroke
				(width 0.1)
				(type default)
			)
			(layer "F.Fab")
		)
		(fp_line
			(start -0.67945 0.3048)
			(end -0.67945 -0.305054)
			(stroke
				(width 0.1)
				(type default)
			)
			(layer "F.Fab")
		)
		(fp_line
			(start -0.12065 -0.305054)
			(end -0.12065 -0.2794)
			(stroke
				(width 0.1)
				(type default)
			)
			(layer "F.Fab")
		)
		(fp_line
			(start -0.12065 -0.2794)
			(end 0.12065 -0.2794)
			(stroke
				(width 0.1)
				(type default)
			)
			(layer "F.Fab")
		)
		(fp_line
			(start -0.12065 0.2794)
			(end -0.12065 0.3048)
			(stroke
				(width 0.1)
				(type default)
			)
			(layer "F.Fab")
		)
		(fp_line
			(start -0.12065 0.3048)
			(end -0.67945 0.3048)
			(stroke
				(width 0.1)
				(type default)
			)
			(layer "F.Fab")
		)
		(fp_line
			(start 0.120396 0.2794)
			(end -0.12065 0.2794)
			(stroke
				(width 0.1)
				(type default)
			)
			(layer "F.Fab")
		)
		(fp_line
			(start 0.120396 0.3048)
			(end 0.120396 0.2794)
			(stroke
				(width 0.1)
				(type default)
			)
			(layer "F.Fab")
		)
		(fp_line
			(start 0.12065 -0.3048)
			(end 0.67945 -0.3048)
			(stroke
				(width 0.1)
				(type default)
			)
			(layer "F.Fab")
		)
		(fp_line
			(start 0.12065 -0.2794)
			(end 0.12065 -0.3048)
			(stroke
				(width 0.1)
				(type default)
			)
			(layer "F.Fab")
		)
		(fp_line
			(start 0.67945 -0.3048)
			(end 0.67945 0.3048)
			(stroke
				(width 0.1)
				(type default)
			)
			(layer "F.Fab")
		)
		(fp_line
			(start 0.67945 0.3048)
			(end 0.120396 0.3048)
			(stroke
				(width 0.1)
				(type default)
			)
			(layer "F.Fab")
		)
		(pad "1" smd circle
			(at -0.40005 0)
			(size 0 0)
			(layers "F.Cu" "F.Mask" "F.Paste")
			(net "P3V3_AUX")
		)
		(pad "2" smd circle
			(at 0.40005 0)
			(size 0 0)
			(layers "F.Cu" "F.Mask" "F.Paste")
			(net "GND")
		)
	)
	(footprint ""
		(layer "F.Cu")
		(at 423.841164 -16.100298 90)
		(property "Reference" "C1572"
			(at 0 0 90)
			(layer "F.SilkS")
			(hide yes)
			(effects
				(font
					(size 1.27 1.27)
				)
			)
		)
		(property "Value" ""
			(at 0 0 90)
			(layer "F.Fab")
			(effects
				(font
					(size 1.27 1.27)
				)
			)
		)
		(duplicate_pad_numbers_are_jumpers no)
		(fp_line
			(start 0.299974 -0.150114)
			(end 0.299974 0.150114)
			(stroke
				(width 0.1)
				(type default)
			)
			(layer "F.Fab")
		)
		(fp_line
			(start -0.299974 -0.150114)
			(end 0.299974 -0.150114)
			(stroke
				(width 0.1)
				(type default)
			)
			(layer "F.Fab")
		)
		(fp_line
			(start 0.299974 0.150114)
			(end -0.299974 0.150114)
			(stroke
				(width 0.1)
				(type default)
			)
			(layer "F.Fab")
		)
		(fp_line
			(start -0.299974 0.150114)
			(end -0.299974 -0.150114)
			(stroke
				(width 0.1)
				(type default)
			)
			(layer "F.Fab")
		)
		(pad "1" smd rect
			(at -0.2667 0 90)
			(size 0.3048 0.381)
			(layers "F.Cu" "F.Mask" "F.Paste")
			(net "P5E_CPU0_G3_TX_C_DN<3>")
		)
		(pad "2" smd rect
			(at 0.2667 0 90)
			(size 0.3048 0.381)
			(layers "F.Cu" "F.Mask" "F.Paste")
			(net "P5E_CPU0_G3_TX_DN<3>")
		)
	)
)
